(kicad_pcb
	(version 20241229)
	(generator "pcbnew")
	(generator_version "9.0")
	(general
		(thickness 1.62)
		(legacy_teardrops no)
	)
	(paper "A3")
	(title_block
		(title "COM Express 7 Baseboard")
		(date "2025-02-04")
		(rev "1.1.2")
		(company "Antmicro Ltd")
		(comment 1 "www.antmicro.com")
		(comment 9 "footprints 286-291 of 802")
	)
	(layers
		(0 "F.Cu" signal)
		(4 "In1.Cu" signal)
		(6 "In2.Cu" signal)
		(8 "In3.Cu" signal)
		(10 "In4.Cu" signal)
		(12 "In5.Cu" signal)
		(14 "In6.Cu" signal)
		(2 "B.Cu" signal)
		(9 "F.Adhes" user "F.Adhesive")
		(11 "B.Adhes" user "B.Adhesive")
		(13 "F.Paste" user)
		(15 "B.Paste" user)
		(5 "F.SilkS" user "F.Silkscreen")
		(7 "B.SilkS" user "B.Silkscreen")
		(1 "F.Mask" user)
		(3 "B.Mask" user)
		(17 "Dwgs.User" user "User.Drawings")
		(19 "Cmts.User" user "User.Comments")
		(21 "Eco1.User" user "User.Eco1")
		(23 "Eco2.User" user "User.Eco2")
		(25 "Edge.Cuts" user)
		(27 "Margin" user)
		(31 "F.CrtYd" user "F.Courtyard")
		(29 "B.CrtYd" user "B.Courtyard")
		(35 "F.Fab" user)
		(33 "B.Fab" user)
	)
	(footprint "antmicro-footprints:R_0402_1005Metric"
		(layer "F.Cu")
		(at 143.45 85.06 180)
		(descr "Resistor SMD 0402")
		(tags "resistor SMD 0402")
		(property "Reference" "R135"
			(at 0.85 -0.45 0)
			(layer "F.SilkS")
			(effects
				(font
					(size 0.7 0.7)
					(thickness 0.15)
				)
				(justify right bottom)
			)
		)
		(property "Value" "R_10k_0402"
			(at -1.011843 1.772047 0)
			(layer "F.Fab")
			(effects
				(font
					(size 0.7 0.7)
					(thickness 0.15)
				)
				(justify right bottom)
			)
		)
		(property "Datasheet" "https://www.bourns.com/docs/product-datasheets/cr.pdf"
			(at 0 0 180)
			(layer "F.Fab")
			(hide yes)
			(effects
				(font
					(size 1.27 1.27)
					(thickness 0.15)
				)
			)
		)
		(property "Author" "Antmicro"
			(at 286.9 170.12 0)
			(layer "F.Fab")
			(hide yes)
			(effects
				(font
					(size 1 1)
					(thickness 0.15)
				)
			)
		)
		(property "License" "Apache-2.0"
			(at 286.9 170.12 0)
			(layer "F.Fab")
			(hide yes)
			(effects
				(font
					(size 1 1)
					(thickness 0.15)
				)
			)
		)
		(property "MPN" "CR0402-FX-1002GLF"
			(at 286.9 170.12 0)
			(layer "F.Fab")
			(hide yes)
			(effects
				(font
					(size 1 1)
					(thickness 0.15)
				)
			)
		)
		(property "Manufacturer" "Bourns"
			(at 286.9 170.12 0)
			(layer "F.Fab")
			(hide yes)
			(effects
				(font
					(size 1 1)
					(thickness 0.15)
				)
			)
		)
		(property "Public" "False"
			(at 286.9 170.12 0)
			(layer "F.Fab")
			(hide yes)
			(effects
				(font
					(size 1 1)
					(thickness 0.15)
				)
			)
		)
		(property "Tolerance" "1%"
			(at 286.9 170.12 0)
			(layer "F.Fab")
			(hide yes)
			(effects
				(font
					(size 1 1)
					(thickness 0.15)
				)
			)
		)
		(property "Val" "10k"
			(at 286.9 170.12 0)
			(layer "F.Fab")
			(hide yes)
			(effects
				(font
					(size 1 1)
					(thickness 0.15)
				)
			)
		)
		(sheetname "M.2 key E")
		(sheetfile "m2keye.kicad_sch")
		(attr smd dnp)
		(fp_rect
			(start -0.925 -0.47)
			(end 0.925 0.47)
			(stroke
				(width 0.05)
				(type default)
			)
			(fill no)
			(layer "F.CrtYd")
		)
		(fp_rect
			(start -0.5 -0.25)
			(end 0.5 0.25)
			(stroke
				(width 0.15)
				(type solid)
			)
			(fill no)
			(layer "F.Fab")
		)
		(pad "1" smd roundrect
			(at -0.48 0 180)
			(size 0.59 0.64)
			(layers "F.Cu" "F.Mask" "F.Paste")
			(roundrect_rratio 0.25)
			(net 23 "/M.2 key E/~{PERST_D}")
			(pintype "passive")
			(teardrops
				(best_length_ratio 0.2)
				(max_length 1)
				(best_width_ratio 0.9)
				(max_width 2)
				(curved_edges yes)
				(filter_ratio 0.9)
				(enabled yes)
				(allow_two_segments yes)
				(prefer_zone_connections yes)
			)
		)
		(pad "2" smd roundrect
			(at 0.48 0 180)
			(size 0.59 0.64)
			(layers "F.Cu" "F.Mask" "F.Paste")
			(roundrect_rratio 0.25)
			(net 2 "+3V3")
			(pintype "passive")
			(teardrops
				(best_length_ratio 0.2)
				(max_length 1)
				(best_width_ratio 0.9)
				(max_width 2)
				(curved_edges yes)
				(filter_ratio 0.9)
				(enabled yes)
				(allow_two_segments yes)
				(prefer_zone_connections yes)
			)
		)
	)
	(footprint "antmicro-footprints:Mech_M2_2280_H2.5mm"
		(layer "F.Cu")
		(at 295.4495 157.485 180)
		(property "Reference" "A1"
			(at 0 8.89 0)
			(layer "F.SilkS")
			(hide yes)
			(effects
				(font
					(size 0.7 0.7)
					(thickness 0.15)
				)
				(justify left bottom)
			)
		)
		(property "Value" "Mech_M2_2280_H2.5mm"
			(at 0 6.857 0)
			(layer "F.Fab")
			(effects
				(font
					(size 0.7 0.7)
					(thickness 0.15)
				)
				(justify left bottom)
			)
		)
		(property "Author" "Antmicro"
			(at 590.899 314.97 0)
			(layer "F.Fab")
			(hide yes)
			(effects
				(font
					(size 1 1)
					(thickness 0.15)
				)
			)
		)
		(property "License" "Apache-2.0"
			(at 590.899 314.97 0)
			(layer "F.Fab")
			(hide yes)
			(effects
				(font
					(size 1 1)
					(thickness 0.15)
				)
			)
		)
		(property "MPN" ""
			(at 590.899 314.97 0)
			(layer "F.Fab")
			(hide yes)
			(effects
				(font
					(size 1 1)
					(thickness 0.15)
				)
			)
		)
		(property "Manufacturer" ""
			(at 590.899 314.97 0)
			(layer "F.Fab")
			(hide yes)
			(effects
				(font
					(size 1 1)
					(thickness 0.15)
				)
			)
		)
		(property "Public" "False"
			(at 590.899 314.97 0)
			(layer "F.Fab")
			(hide yes)
			(effects
				(font
					(size 1 1)
					(thickness 0.15)
				)
			)
		)
		(sheetname "M.2 key M #2")
		(sheetfile "m2keym.kicad_sch")
		(attr exclude_from_pos_files exclude_from_bom allow_missing_courtyard)
		(fp_rect
			(start -10.922 0.0508)
			(end 11.0236 80.0608)
			(stroke
				(width 0.15)
				(type solid)
			)
			(fill no)
			(layer "F.Fab")
		)
	)
	(footprint "antmicro-footprints:R_0201"
		(layer "F.Cu")
		(at 156.332 147.935 -90)
		(descr "Resistor SMD 0201")
		(tags "resistor SMD 0201")
		(property "Reference" "R254"
			(at 6.495 -0.618 270)
			(layer "F.SilkS")
			(effects
				(font
					(size 0.7 0.7)
					(thickness 0.15)
				)
				(justify left bottom)
			)
		)
		(property "Value" "R_0R_0201"
			(at 0 1.25 270)
			(layer "F.Fab")
			(effects
				(font
					(size 0.7 0.7)
					(thickness 0.15)
				)
				(justify left bottom)
			)
		)
		(property "Datasheet" "https://www.bourns.com/docs/product-datasheets/cr.pdf"
			(at 0 0 270)
			(layer "F.Fab")
			(hide yes)
			(effects
				(font
					(size 1.27 1.27)
					(thickness 0.15)
				)
			)
		)
		(property "Author" "Antmicro"
			(at 8.397 304.267 0)
			(layer "F.Fab")
			(hide yes)
			(effects
				(font
					(size 1 1)
					(thickness 0.15)
				)
			)
		)
		(property "License" "Apache-2.0"
			(at 8.397 304.267 0)
			(layer "F.Fab")
			(hide yes)
			(effects
				(font
					(size 1 1)
					(thickness 0.15)
				)
			)
		)
		(property "MPN" "CR0201-FX-0R00GLF"
			(at 8.397 304.267 0)
			(layer "F.Fab")
			(hide yes)
			(effects
				(font
					(size 1 1)
					(thickness 0.15)
				)
			)
		)
		(property "Manufacturer" "Bourns"
			(at 8.397 304.267 0)
			(layer "F.Fab")
			(hide yes)
			(effects
				(font
					(size 1 1)
					(thickness 0.15)
				)
			)
		)
		(property "Tolerance" "1%"
			(at 8.397 304.267 0)
			(layer "F.Fab")
			(hide yes)
			(effects
				(font
					(size 1 1)
					(thickness 0.15)
				)
			)
		)
		(property "Val" "0R"
			(at 8.397 304.267 0)
			(layer "F.Fab")
			(hide yes)
			(effects
				(font
					(size 1 1)
					(thickness 0.15)
				)
			)
		)
		(sheetname "KR to SFI #1")
		(sheetfile "kr_sfi.kicad_sch")
		(attr smd dnp)
		(fp_rect
			(start -0.7 -0.35)
			(end 0.7 0.35)
			(stroke
				(width 0.05)
				(type default)
			)
			(fill no)
			(layer "F.CrtYd")
		)
		(fp_rect
			(start -0.3 -0.15)
			(end 0.298 0.148)
			(stroke
				(width 0.15)
				(type solid)
			)
			(fill no)
			(layer "F.Fab")
		)
		(pad "" smd roundrect
			(at -0.346 0 270)
			(size 0.318 0.36)
			(layers "F.Paste")
			(roundrect_rratio 0.25)
			(teardrops
				(best_length_ratio 0.2)
				(max_length 1)
				(best_width_ratio 0.9)
				(max_width 2)
				(curved_edges yes)
				(filter_ratio 0.9)
				(enabled yes)
				(allow_two_segments yes)
				(prefer_zone_connections yes)
			)
		)
		(pad "" smd roundrect
			(at 0.344 0 270)
			(size 0.318 0.36)
			(layers "F.Paste")
			(roundrect_rratio 0.25)
			(teardrops
				(best_length_ratio 0.2)
				(max_length 1)
				(best_width_ratio 0.9)
				(max_width 2)
				(curved_edges yes)
				(filter_ratio 0.9)
				(enabled yes)
				(allow_two_segments yes)
				(prefer_zone_connections yes)
			)
		)
		(pad "1" smd roundrect
			(at -0.32 0 270)
			(size 0.46 0.4)
			(layers "F.Cu" "F.Mask")
			(roundrect_rratio 0.25)
			(net 113 "/2xSFP+/10GKR_SFP0.TX-")
			(pintype "passive")
			(teardrops
				(best_length_ratio 0.2)
				(max_length 1)
				(best_width_ratio 0.9)
				(max_width 2)
				(curved_edges yes)
				(filter_ratio 0.9)
				(enabled yes)
				(allow_two_segments yes)
				(prefer_zone_connections yes)
			)
		)
		(pad "2" smd roundrect
			(at 0.32 0 270)
			(size 0.46 0.4)
			(layers "F.Cu" "F.Mask")
			(roundrect_rratio 0.25)
			(net 948 "/2xSFP+/KR to SFI #1/BYP_TX-")
			(pintype "passive")
			(teardrops
				(best_length_ratio 0.2)
				(max_length 1)
				(best_width_ratio 0.9)
				(max_width 2)
				(curved_edges yes)
				(filter_ratio 0.9)
				(enabled yes)
				(allow_two_segments yes)
				(prefer_zone_connections yes)
			)
		)
	)
	(footprint "antmicro-footprints:C_0402_1005Metric"
		(layer "F.Cu")
		(at 261.54 87.949999 90)
		(descr "Capacitor SMD 0402")
		(tags "capacitor SMD 0402")
		(property "Reference" "C83"
			(at -1.060001 1.36 90)
			(layer "F.SilkS")
			(effects
				(font
					(size 0.7 0.7)
					(thickness 0.15)
				)
				(justify left bottom)
			)
		)
		(property "Value" "C_100n_0402"
			(at -1.022927 2.155213 90)
			(layer "F.Fab")
			(effects
				(font
					(size 0.7 0.7)
					(thickness 0.15)
				)
				(justify left bottom)
			)
		)
		(property "Datasheet" "https://www.murata.com/products/productdetail?partno=GRM155R61H104KE14%23"
			(at 0 0 90)
			(layer "F.Fab")
			(hide yes)
			(effects
				(font
					(size 1.27 1.27)
					(thickness 0.15)
				)
			)
		)
		(property "Author" "Antmicro"
			(at 349.489999 -173.590001 0)
			(layer "F.Fab")
			(hide yes)
			(effects
				(font
					(size 1 1)
					(thickness 0.15)
				)
			)
		)
		(property "Dielectric" "X5R"
			(at 349.489999 -173.590001 0)
			(layer "F.Fab")
			(hide yes)
			(effects
				(font
					(size 1 1)
					(thickness 0.15)
				)
			)
		)
		(property "License" "Apache-2.0"
			(at 349.489999 -173.590001 0)
			(layer "F.Fab")
			(hide yes)
			(effects
				(font
					(size 1 1)
					(thickness 0.15)
				)
			)
		)
		(property "MPN" "GRM155R61H104KE14D"
			(at 349.489999 -173.590001 0)
			(layer "F.Fab")
			(hide yes)
			(effects
				(font
					(size 1 1)
					(thickness 0.15)
				)
			)
		)
		(property "Manufacturer" "Murata"
			(at 349.489999 -173.590001 0)
			(layer "F.Fab")
			(hide yes)
			(effects
				(font
					(size 1 1)
					(thickness 0.15)
				)
			)
		)
		(property "Public" "False"
			(at 349.489999 -173.590001 0)
			(layer "F.Fab")
			(hide yes)
			(effects
				(font
					(size 1 1)
					(thickness 0.15)
				)
			)
		)
		(property "Val" "100n"
			(at 349.489999 -173.590001 0)
			(layer "F.Fab")
			(hide yes)
			(effects
				(font
					(size 1 1)
					(thickness 0.15)
				)
			)
		)
		(property "Voltage" "50V"
			(at 349.489999 -173.590001 0)
			(layer "F.Fab")
			(hide yes)
			(effects
				(font
					(size 1 1)
					(thickness 0.15)
				)
			)
		)
		(sheetname "Misc")
		(sheetfile "misc.kicad_sch")
		(attr smd)
		(fp_rect
			(start -0.925 -0.47)
			(end 0.925 0.47)
			(stroke
				(width 0.05)
				(type default)
			)
			(fill no)
			(layer "F.CrtYd")
		)
		(fp_line
			(start 0.504 -0.25)
			(end 0.504 0.248)
			(stroke
				(width 0.15)
				(type solid)
			)
			(layer "F.Fab")
		)
		(fp_line
			(start -0.494 -0.25)
			(end 0.504 -0.25)
			(stroke
				(width 0.15)
				(type solid)
			)
			(layer "F.Fab")
		)
		(fp_line
			(start 0.504 0.248)
			(end -0.494 0.248)
			(stroke
				(width 0.15)
				(type solid)
			)
			(layer "F.Fab")
		)
		(fp_line
			(start -0.494 0.248)
			(end -0.494 -0.25)
			(stroke
				(width 0.15)
				(type solid)
			)
			(layer "F.Fab")
		)
		(pad "1" smd roundrect
			(at -0.48 0 90)
			(size 0.59 0.64)
			(layers "F.Cu" "F.Mask" "F.Paste")
			(roundrect_rratio 0.25)
			(net 1 "GND")
			(pintype "passive")
			(teardrops
				(best_length_ratio 0.2)
				(max_length 1)
				(best_width_ratio 0.9)
				(max_width 2)
				(curved_edges yes)
				(filter_ratio 0.9)
				(enabled yes)
				(allow_two_segments yes)
				(prefer_zone_connections yes)
			)
		)
		(pad "2" smd roundrect
			(at 0.48 0 90)
			(size 0.59 0.64)
			(layers "F.Cu" "F.Mask" "F.Paste")
			(roundrect_rratio 0.25)
			(net 80 "Net-(Q6-D)")
			(pintype "passive")
			(teardrops
				(best_length_ratio 0.2)
				(max_length 1)
				(best_width_ratio 0.9)
				(max_width 2)
				(curved_edges yes)
				(filter_ratio 0.9)
				(enabled yes)
				(allow_two_segments yes)
				(prefer_zone_connections yes)
			)
		)
	)
	(footprint "antmicro-footprints:R_0402_1005Metric"
		(layer "F.Cu")
		(at 297.2 84.03 90)
		(descr "Resistor SMD 0402")
		(tags "resistor SMD 0402")
		(property "Reference" "R126"
			(at -3.68 0.45 90)
			(layer "F.SilkS")
			(effects
				(font
					(size 0.7 0.7)
					(thickness 0.15)
				)
				(justify left bottom)
			)
		)
		(property "Value" "R_0R_0402"
			(at -1.011843 1.772047 90)
			(layer "F.Fab")
			(effects
				(font
					(size 0.7 0.7)
					(thickness 0.15)
				)
				(justify left bottom)
			)
		)
		(property "Datasheet" "https://industrial.panasonic.com/cdbs/www-data/pdf/RDA0000/AOA0000C301.pdf"
			(at 0 0 90)
			(layer "F.Fab")
			(hide yes)
			(effects
				(font
					(size 1.27 1.27)
					(thickness 0.15)
				)
			)
		)
		(property "Author" "Antmicro"
			(at 381.23 -213.17 0)
			(layer "F.Fab")
			(hide yes)
			(effects
				(font
					(size 1 1)
					(thickness 0.15)
				)
			)
		)
		(property "Current" "1A"
			(at 381.23 -213.17 0)
			(layer "F.Fab")
			(hide yes)
			(effects
				(font
					(size 1 1)
					(thickness 0.15)
				)
			)
		)
		(property "License" "Apache-2.0"
			(at 381.23 -213.17 0)
			(layer "F.Fab")
			(hide yes)
			(effects
				(font
					(size 1 1)
					(thickness 0.15)
				)
			)
		)
		(property "MPN" "ERJ2GE0R00X"
			(at 381.23 -213.17 0)
			(layer "F.Fab")
			(hide yes)
			(effects
				(font
					(size 1 1)
					(thickness 0.15)
				)
			)
		)
		(property "Manufacturer" "Panasonic"
			(at 381.23 -213.17 0)
			(layer "F.Fab")
			(hide yes)
			(effects
				(font
					(size 1 1)
					(thickness 0.15)
				)
			)
		)
		(property "Public" "False"
			(at 381.23 -213.17 0)
			(layer "F.Fab")
			(hide yes)
			(effects
				(font
					(size 1 1)
					(thickness 0.15)
				)
			)
		)
		(property "Tolerance" ""
			(at 381.23 -213.17 0)
			(layer "F.Fab")
			(hide yes)
			(effects
				(font
					(size 1 1)
					(thickness 0.15)
				)
			)
		)
		(property "Val" "0R"
			(at 381.23 -213.17 0)
			(layer "F.Fab")
			(hide yes)
			(effects
				(font
					(size 1 1)
					(thickness 0.15)
				)
			)
		)
		(sheetname "M.2 key M #2")
		(sheetfile "m2keym.kicad_sch")
		(attr smd)
		(fp_rect
			(start -0.925 -0.47)
			(end 0.925 0.47)
			(stroke
				(width 0.05)
				(type default)
			)
			(fill no)
			(layer "F.CrtYd")
		)
		(fp_rect
			(start -0.5 -0.25)
			(end 0.5 0.25)
			(stroke
				(width 0.15)
				(type solid)
			)
			(fill no)
			(layer "F.Fab")
		)
		(pad "1" smd roundrect
			(at -0.48 0 90)
			(size 0.59 0.64)
			(layers "F.Cu" "F.Mask" "F.Paste")
			(roundrect_rratio 0.25)
			(net 528 "/Backplane/~{PERST}")
			(pintype "passive")
			(teardrops
				(best_length_ratio 0.2)
				(max_length 1)
				(best_width_ratio 0.9)
				(max_width 2)
				(curved_edges yes)
				(filter_ratio 0.9)
				(enabled yes)
				(allow_two_segments yes)
				(prefer_zone_connections yes)
			)
		)
		(pad "2" smd roundrect
			(at 0.48 0 90)
			(size 0.59 0.64)
			(layers "F.Cu" "F.Mask" "F.Paste")
			(roundrect_rratio 0.25)
			(net 270 "/M.2 key M #2/~{PERST_D}")
			(pintype "passive")
			(teardrops
				(best_length_ratio 0.2)
				(max_length 1)
				(best_width_ratio 0.9)
				(max_width 2)
				(curved_edges yes)
				(filter_ratio 0.9)
				(enabled yes)
				(allow_two_segments yes)
				(prefer_zone_connections yes)
			)
		)
	)
	(footprint "antmicro-footprints:TP_SMD_0.75mm"
		(layer "F.Cu")
		(at 149.85 129.56)
		(property "Reference" "TP71"
			(at 0.45 -1.25 90)
			(layer "F.SilkS")
			(effects
				(font
					(size 0.7 0.7)
					(thickness 0.15)
				)
				(justify left bottom)
			)
		)
		(property "Value" "TP_0.75mm_SMD"
			(at 0 1.2 0)
			(layer "F.Fab")
			(effects
				(font
					(size 0.7 0.7)
					(thickness 0.15)
				)
				(justify left bottom)
			)
		)
		(property "Author" "Antmicro"
			(at 0 0 0)
			(layer "F.Fab")
			(hide yes)
			(effects
				(font
					(size 1 1)
					(thickness 0.15)
				)
			)
		)
		(property "License" "Apache-2.0"
			(at 0 0 0)
			(layer "F.Fab")
			(hide yes)
			(effects
				(font
					(size 1 1)
					(thickness 0.15)
				)
			)
		)
		(property "MPN" ""
			(at 0 0 0)
			(layer "F.Fab")
			(hide yes)
			(effects
				(font
					(size 1 1)
					(thickness 0.15)
				)
			)
		)
		(property "Manufacturer" ""
			(at 0 0 0)
			(layer "F.Fab")
			(hide yes)
			(effects
				(font
					(size 1 1)
					(thickness 0.15)
				)
			)
		)
		(property "Public" "False"
			(at 0 0 0)
			(layer "F.Fab")
			(hide yes)
			(effects
				(font
					(size 1 1)
					(thickness 0.15)
				)
			)
		)
		(sheetname "KR to SFI #1")
		(sheetfile "kr_sfi.kicad_sch")
		(attr exclude_from_pos_files exclude_from_bom)
		(fp_circle
			(center 0 0)
			(end 0.475 0)
			(stroke
				(width 0.05)
				(type default)
			)
			(fill no)
			(layer "F.CrtYd")
		)
		(pad "1" smd circle
			(at 0 0)
			(size 0.75 0.75)
			(layers "F.Cu" "F.Mask")
			(net 734 "Net-(U43A-LOSA)")
			(pinfunction "1")
			(pintype "passive")
			(teardrops
				(best_length_ratio 0.4)
				(max_length 1)
				(best_width_ratio 0.9)
				(max_width 2)
				(curved_edges yes)
				(filter_ratio 0.9)
				(enabled yes)
				(allow_two_segments yes)
				(prefer_zone_connections yes)
			)
		)
	)
)
